# T6G (Grand Teton) — schematic parts with pin connectivity, parts 7133–7288 of 8303; source: Cadence DE-HDL packaged netlist (pstxprt.dat, pstxnet.dat, pstchip.dat)

R4119  Q_RES  54.9K 1% EMPTY  pkg 0402LF  page 125 : 1 = P3V3_AUX ; 2 = GPU_3V3IO_RSVD0_FFU
R4120  Q_RES  100K 1% EMPTY  pkg 0402LF  page 125 : 1 = GPU_3V3IO_RSVD0_FFU ; 2 = GND
R4121  Q_RES  10K 1% CHIP  pkg 0402LF  page 125 : 1 = P3V3_AUX ; 2 = PRSNT_CABLE_GPU_B3_N
R4122  Q_RES  100K 1% EMPTY  pkg 0402LF  page 125 : 1 = PRSNT_CABLE_GPU_B3_N ; 2 = GND
R4123  Q_RES  54.9K 1% EMPTY  pkg 0402LF  page 125 : 1 = P3V3_AUX ; 2 = GPU_3V3IO_RSVD1_FFU
R4124  Q_RES  100K 1% EMPTY  pkg 0402LF  page 125 : 1 = GPU_3V3IO_RSVD1_FFU ; 2 = GND
R4125  Q_RES  4.7K 5% CHIP  pkg 0402LF  page 125 : 1 = P3V3_AUX ; 2 = GPU_3V3IO_RSVD0_FFU_N
R4126  Q_RES  4.7K 5% CHIP  pkg 0402LF  page 125 : 1 = P3V3_AUX ; 2 = PRSNT_CABLE_GPU_B3
R4127  Q_RES  4.7K 5% CHIP  pkg 0402LF  page 125 : 1 = P3V3_AUX ; 2 = GPU_3V3IO_RSVD1_FFU_N
R4128  Q_RES  100K 1% CHIP  pkg 0402LF  page 125 : 1 = P3V3_AUX ; 2 = GPU_3V3IO_RSVD0_FFU_ISO
R4129  Q_RES  100K 1% CHIP  pkg 0402LF  page 125 : 1 = P3V3_AUX ; 2 = PRSNT_CABLE_GPU_B3_ISO_N
R4130  Q_RES  100K 1% CHIP  pkg 0402LF  page 125 : 1 = P3V3_AUX ; 2 = GPU_3V3IO_RSVD1_FFU_ISO
R4131  Q_RES  54.9K 1% EMPTY  pkg 0402LF  page 125 : 1 = P3V3_AUX ; 2 = GPU_3V3IO_RSVD3_FFU
R4132  Q_RES  100K 1% EMPTY  pkg 0402LF  page 125 : 1 = GPU_3V3IO_RSVD3_FFU ; 2 = GND
R4133  Q_RES  54.9K 1% EMPTY  pkg 0402LF  page 125 : 1 = P3V3_AUX ; 2 = GPU_3V3IO_RSVD5_FFU
R4134  Q_RES  100K 1% EMPTY  pkg 0402LF  page 125 : 1 = GPU_3V3IO_RSVD5_FFU ; 2 = GND
R4135  Q_RES  10K 1% CHIP  pkg 0402LF  page 125 : 1 = P3V3_AUX ; 2 = PRSNT_CABLE_GPU_A2_N
R4136  Q_RES  100K 1% EMPTY  pkg 0402LF  page 125 : 1 = PRSNT_CABLE_GPU_A2_N ; 2 = GND
R4137  Q_RES  4.7K 5% CHIP  pkg 0402LF  page 125 : 1 = P3V3_AUX ; 2 = GPU_3V3IO_RSVD3_FFU_N
R4138  Q_RES  4.7K 5% CHIP  pkg 0402LF  page 125 : 1 = P3V3_AUX ; 2 = GPU_3V3IO_RSVD5_FFU_N
R4139  Q_RES  4.7K 5% CHIP  pkg 0402LF  page 125 : 1 = P3V3_AUX ; 2 = PRSNT_CABLE_GPU_A2
R4140  Q_RES  100K 1% CHIP  pkg 0402LF  page 125 : 1 = P3V3_AUX ; 2 = GPU_3V3IO_RSVD3_FFU_ISO
R4141  Q_RES  100K 1% CHIP  pkg 0402LF  page 125 : 1 = P3V3_AUX ; 2 = GPU_3V3IO_RSVD5_FFU_ISO
R4142  Q_RES  100K 1% CHIP  pkg 0402LF  page 125 : 1 = P3V3_AUX ; 2 = PRSNT_CABLE_GPU_A2_ISO_N
R4143  Q_RES  33.2 1% CHIP  pkg 0402LF  page 81 : 1 = GPU_3V3IO_RSVD0_FFU_ISO_R ; 2 = GPU_3V3IO_RSVD0_FFU_ISO
R4144  Q_RES  33.2 1% CHIP  pkg 0402LF  page 81 : 1 = GPU_3V3IO_RSVD1_FFU_ISO_R ; 2 = GPU_3V3IO_RSVD1_FFU_ISO
R4145  Q_RES  33.2 1% CHIP  pkg 0402LF  page 80 : 1 = PRSNT_CABLE_GPU_B3_ISO_R_N ; 2 = PRSNT_CABLE_GPU_B3_ISO_N
R4146  Q_RES  33.2 1% CHIP  pkg 0402LF  page 80 : 1 = GPU_3V3IO_RSVD3_FFU_ISO_R ; 2 = GPU_3V3IO_RSVD3_FFU_ISO
R4147  Q_RES  33.2 1% CHIP  pkg 0402LF  page 81 : 1 = PRSNT_CABLE_GPU_A2_ISO_R_N ; 2 = PRSNT_CABLE_GPU_A2_ISO_N
R4148  Q_RES  33.2 1% CHIP  pkg 0402LF  page 81 : 1 = GPU_3V3IO_RSVD5_FFU_ISO_R ; 2 = GPU_3V3IO_RSVD5_FFU_ISO
R4149  Q_RES  33.2 1% CHIP  pkg 0402LF  page 151 : 1 = SMB_1_PLD_3V3AUX_SCL ; 2 = SMB_1_PLD_3V3AUX_SCL_R1
R4150  Q_RES  33.2 1% CHIP  pkg 0402LF  page 151 : 1 = SMB_1_PLD_3V3AUX_SDA ; 2 = SMB_1_PLD_3V3AUX_SDA_R1
R4151  Q_RES  33.2 1% CHIP  pkg 0402LF  page 151 : 1 = SMB_1_PLD_3V3AUX_SCL ; 2 = SMB_2_PLD_3V3AUX_SCL_R1
R4152  Q_RES  33.2 1% CHIP  pkg 0402LF  page 151 : 1 = SMB_1_PLD_3V3AUX_SDA ; 2 = SMB_2_PLD_3V3AUX_SDA_R1
R4153  Q_RES  10K 1% CHIP  pkg 0402LF  page 125 : 1 = P3V3_AUX ; 2 = PRSNT_CABLE_GPU_A1_N
R4154  Q_RES  100K 1% EMPTY  pkg 0402LF  page 125 : 1 = PRSNT_CABLE_GPU_A1_N ; 2 = GND
R4155  Q_RES  4.7K 5% CHIP  pkg 0402LF  page 125 : 1 = P3V3_AUX ; 2 = PRSNT_CABLE_GPU_A1
R4156  Q_RES  100K 1% CHIP  pkg 0402LF  page 125 : 1 = P3V3_AUX ; 2 = PRSNT_CABLE_GPU_A1_ISO_N
R4157  Q_RES  33.2 1% CHIP  pkg 0402LF  page 81 : 1 = PRSNT_CABLE_GPU_A1_ISO_R_N ; 2 = PRSNT_CABLE_GPU_A1_ISO_N
R4158  Q_RES  54.9K 1% EMPTY  pkg 0402LF  page 124 : 1 = P3V3_AUX ; 2 = GPU_3V3IO_RSVD1
R4159  Q_RES  100K 1% EMPTY  pkg 0402LF  page 124 : 1 = GPU_3V3IO_RSVD1 ; 2 = GND
R4160  Q_RES  54.9K 1% EMPTY  pkg 0402LF  page 124 : 1 = P3V3_AUX ; 2 = GPU_3V3IO_RSVD4
R4161  Q_RES  100K 1% EMPTY  pkg 0402LF  page 124 : 1 = GPU_3V3IO_RSVD4 ; 2 = GND
R4162  Q_RES  54.9K 1% EMPTY  pkg 0402LF  page 124 : 1 = P3V3_AUX ; 2 = GPU_3V3IO_RSVD3
R4163  Q_RES  100K 1% EMPTY  pkg 0402LF  page 124 : 1 = GPU_3V3IO_RSVD3 ; 2 = GND
R4164  Q_RES  4.7K 5% CHIP  pkg 0402LF  page 124 : 1 = P3V3_AUX ; 2 = GPU_3V3IO_RSVD1_N
R4165  Q_RES  4.7K 5% CHIP  pkg 0402LF  page 124 : 1 = P3V3_AUX ; 2 = GPU_3V3IO_RSVD4_N
R4166  Q_RES  4.7K 5% CHIP  pkg 0402LF  page 124 : 1 = P3V3_AUX ; 2 = GPU_3V3IO_RSVD3_N
R4167  Q_RES  100K 1% CHIP  pkg 0402LF  page 124 : 1 = P3V3_AUX ; 2 = GPU_3V3IO_RSVD1_ISO
R4168  Q_RES  100K 1% CHIP  pkg 0402LF  page 124 : 1 = P3V3_AUX ; 2 = GPU_3V3IO_RSVD4_ISO
R4169  Q_RES  100K 1% CHIP  pkg 0402LF  page 124 : 1 = P3V3_AUX ; 2 = GPU_3V3IO_RSVD3_ISO
R4170  Q_RES  33.2 1% CHIP  pkg 0402LF  page 81 : 1 = GPU_3V3IO_RSVD1_ISO_R ; 2 = GPU_3V3IO_RSVD1_ISO
R4171  Q_RES  33.2 1% CHIP  pkg 0402LF  page 81 : 1 = GPU_3V3IO_RSVD3_ISO_R ; 2 = GPU_3V3IO_RSVD3_ISO
R4172  Q_RES  33.2 1% CHIP  pkg 0402LF  page 81 : 1 = GPU_3V3IO_RSVD4_ISO_R ; 2 = GPU_3V3IO_RSVD4_ISO
R4173  Q_RES  100K 1% EMPTY  pkg 0402LF  page 130 : 1 = P3V3_AUX ; 2 = UART_BMC_BIC_R_BUF_RX
R4178  Q_RES  33.2 1% CHIP  pkg 0402LF  page 235 : 1 = SMB_LM75_2_3V3AUX_SCL ; 2 = SMB_LM75_2_3V3AUX_SCL_R1
R4179  Q_RES  33.2 1% CHIP  pkg 0402LF  page 235 : 1 = SMB_LM75_1_3V3AUX_SCL ; 2 = SMB_LM75_1_3V3AUX_SCL_R1
R4180  Q_RES  33.2 1% CHIP  pkg 0402LF  page 235 : 1 = SMB_LM75_0_3V3AUX_SCL ; 2 = SMB_LM75_0_3V3AUX_SCL_R1
R4181  Q_RES  33.2 1% CHIP  pkg 0402LF  page 235 : 1 = SMB_LM75_2_3V3AUX_SDA ; 2 = SMB_LM75_2_3V3AUX_SDA_R1
R4182  Q_RES  33.2 1% CHIP  pkg 0402LF  page 235 : 1 = SMB_LM75_1_3V3AUX_SDA ; 2 = SMB_LM75_1_3V3AUX_SDA_R1
R4183  Q_RES  33.2 1% CHIP  pkg 0402LF  page 235 : 1 = SMB_LM75_0_3V3AUX_SDA ; 2 = SMB_LM75_0_3V3AUX_SDA_R1
R4184  Q_RES  1K 1% EMPTY  pkg 0402LF  page 235 : 1 = P3V3_AUX ; 2 = U273_3_ADD2
R4185  Q_RES  1K 1% CHIP  pkg 0402LF  page 235 : 1 = U273_3_ADD2 ; 2 = GND
R4186  Q_RES  1K 1% EMPTY  pkg 0402LF  page 235 : 1 = P3V3_AUX ; 2 = U272_2_ADD2
R4187  Q_RES  1K 1% CHIP  pkg 0402LF  page 235 : 1 = U272_2_ADD2 ; 2 = GND
R4188  Q_RES  1K 1% EMPTY  pkg 0402LF  page 235 : 1 = P3V3_AUX ; 2 = U271_1_ADD2
R4189  Q_RES  1K 1% CHIP  pkg 0402LF  page 235 : 1 = U271_1_ADD2 ; 2 = GND
R4190  Q_RES  1K 1% EMPTY  pkg 0402LF  page 235 : 1 = P3V3_AUX ; 2 = U270_0_ADD2
R4191  Q_RES  1K 1% CHIP  pkg 0402LF  page 235 : 1 = U270_0_ADD2 ; 2 = GND
R4192  Q_RES  1K 1% EMPTY  pkg 0402LF  page 235 : 1 = P3V3_AUX ; 2 = U273_3_ADD1
R4193  Q_RES  1K 1% CHIP  pkg 0402LF  page 235 : 1 = U273_3_ADD1 ; 2 = GND
R4194  Q_RES  1K 1% EMPTY  pkg 0402LF  page 235 : 1 = P3V3_AUX ; 2 = U272_2_ADD1
R4195  Q_RES  1K 1% CHIP  pkg 0402LF  page 235 : 1 = U272_2_ADD1 ; 2 = GND
R4196  Q_RES  1K 1% EMPTY  pkg 0402LF  page 235 : 1 = P3V3_AUX ; 2 = U271_1_ADD1
R4197  Q_RES  1K 1% CHIP  pkg 0402LF  page 235 : 1 = U271_1_ADD1 ; 2 = GND
R4198  Q_RES  1K 1% EMPTY  pkg 0402LF  page 235 : 1 = P3V3_AUX ; 2 = U270_0_ADD1
R4199  Q_RES  1K 1% CHIP  pkg 0402LF  page 235 : 1 = U270_0_ADD1 ; 2 = GND
R4200  Q_RES  1K 1% EMPTY  pkg 0402LF  page 235 : 1 = P3V3_AUX ; 2 = U273_3_ADD0
R4201  Q_RES  1K 1% CHIP  pkg 0402LF  page 235 : 1 = U273_3_ADD0 ; 2 = GND
R4202  Q_RES  1K 1% EMPTY  pkg 0402LF  page 235 : 1 = P3V3_AUX ; 2 = U272_2_ADD0
R4203  Q_RES  1K 1% CHIP  pkg 0402LF  page 235 : 1 = U272_2_ADD0 ; 2 = GND
R4204  Q_RES  1K 1% EMPTY  pkg 0402LF  page 235 : 1 = P3V3_AUX ; 2 = U271_1_ADD0
R4205  Q_RES  1K 1% CHIP  pkg 0402LF  page 235 : 1 = U271_1_ADD0 ; 2 = GND
R4206  Q_RES  1K 1% EMPTY  pkg 0402LF  page 235 : 1 = P3V3_AUX ; 2 = U270_0_ADD0
R4207  Q_RES  1K 1% CHIP  pkg 0402LF  page 235 : 1 = U270_0_ADD0 ; 2 = GND
R4208  Q_RES  200K 1% EMPTY  pkg 0402LF  page 235 : 1 = P3V3_AUX ; 2 = FM_THERMAL_ALERT_N
R4209  Q_RES  200K 1% EMPTY  pkg 0402LF  page 235 : 1 = P3V3_AUX ; 2 = FM_THERMAL_ALERT_N
R4210  Q_RES  200K 1% EMPTY  pkg 0402LF  page 235 : 1 = P3V3_AUX ; 2 = FM_THERMAL_ALERT_N
R4211  Q_RES  200K 1% CHIP  pkg 0402LF  page 235 : 1 = P3V3_AUX ; 2 = FM_THERMAL_ALERT_N
R4212  Q_RES  0 5% CHIP  pkg 0402LF  page 235 : 1 = FM_THERMAL_ALERT_N ; 2 = FM_LM75_3_ALERT_N
R4213  Q_RES  0 5% CHIP  pkg 0402LF  page 235 : 1 = FM_THERMAL_ALERT_N ; 2 = FM_LM75_2_ALERT_N
R4214  Q_RES  0 5% CHIP  pkg 0402LF  page 235 : 1 = FM_THERMAL_ALERT_N ; 2 = FM_G751_1_ALERT_N
R4215  Q_RES  0 5% CHIP  pkg 0402LF  page 235 : 1 = FM_THERMAL_ALERT_N ; 2 = FM_G751_0_ALERT_N
R4264  Q_RES  4.7K 5% CHIP  pkg 0402LF  page 241 : 1 = P3V3_AUX ; 2 = PWRGD_P3V3_AUX_PDB_BUF_R
R4265  Q_RES  4.7K 5% EMPTY  pkg 0402LF  page 241 : 1 = PWRGD_P3V3_AUX_PDB_BUF_R ; 2 = GND
R4266  Q_RES  33.2 1% CHIP  pkg 0402LF  page 241 : 1 = PWRGD_P3V3_AUX_PDB_BUF_R ; 2 = PWRGD_P3V3_AUX_PDB_BUF
R4268  Q_RES  0 5% CHIP  pkg 0402LF  page 241 : 1 = PWRGD_P3V3_AUX_PDB ; 2 = PWRGD_P3V3_AUX_PDB_R
R4269  Q_RES  2.2K 5% EMPTY  pkg 0402LF  page 252 : 1 = P3V3_AUX ; 2 = SMB_VR_SENSOR_3V3AUX_SCL
R4270  Q_RES  2.2K 5% EMPTY  pkg 0402LF  page 252 : 1 = P3V3_AUX ; 2 = SMB_VR_SENSOR_3V3AUX_SDA
R4303  Q_RES  0 5% CHIP  pkg 0402LF  page 28 : 1 = CLK_100M_CPU0_CLK12_R_DP ; 2 = CLK_100M_CPU0_CLK12_DP
R4304  Q_RES  0 5% CHIP  pkg 0402LF  page 28 : 1 = CLK_100M_CPU0_CLK12_R_DN ; 2 = CLK_100M_CPU0_CLK12_DN
R4305  Q_RES  0 5% CHIP  pkg 0402LF  page 55 : 1 = CLK_100M_CPU1_CLK12_R_DP ; 2 = CLK_100M_CPU1_CLK12_DP
R4306  Q_RES  0 5% CHIP  pkg 0402LF  page 55 : 1 = CLK_100M_CPU1_CLK12_R_DN ; 2 = CLK_100M_CPU1_CLK12_DN
R4419  Q_RES  49.9 1% EMPTY  pkg 0402LF  page 234 : 1 = USB2_HOST_BMC_B_DP ; 2 = GND
R4420  Q_RES  49.9 1% EMPTY  pkg 0402LF  page 234 : 1 = USB2_HOST_BMC_B_DN ; 2 = GND
R4450  Q_RES  0 5% CHIP  pkg 0402LF  page 176 : 1 = USB_CPU0_HUB1_VBUS_DS ; 2 = P5V_AUX
R4451  Q_RES  33.2 1% CHIP  pkg 0402LF  page 176 : 1 = RST_USB_HUB_N ; 2 = RST_USB_CPU0_HUB1_R_N
R4452  Q_RES  10K 1% EMPTY  pkg 0402LF  page 176 : 1 = P3V3_AUX ; 2 = RST_USB_CPU0_HUB1_R_N
R4453  Q_RES  47K 0.1% EMPTY  pkg 0402LF  page 176 : 1 = RST_USB_CPU0_HUB1_R_N ; 2 = GND
R4475  Q_RES  1 1% CHIP  pkg 0603LF  page 182 : 1 = P3V3_9ZXL045_P0 ; 2 = P3V3_9ZXL045_P0_VDDR
R4476  Q_RES  10K 1% CHIP  pkg 0402LF  page 182 : 1 = P3V3_AUX ; 2 = FM_9ZXL045_P0_DEV_EN
R4482  Q_RES  49.9 1% EMPTY  pkg 0402LF  page 234 : 1 = USB2_HOST_BMC_B_BUF_DP ; 2 = GND
R4483  Q_RES  49.9 1% EMPTY  pkg 0402LF  page 234 : 1 = USB2_HOST_BMC_B_BUF_DN ; 2 = GND
R4489  Q_RES  4.75K 1% CHIP  pkg 0402LF  page 182 : 1 = P3V3_AUX ; 2 = CLK_9ZXL045_P0_SADR0
R4490  Q_RES  4.75K 1% EMPTY  pkg 0402LF  page 182 : 1 = CLK_9ZXL045_P0_SADR0 ; 2 = GND
R4491  Q_RES  10K 1% CHIP  pkg 0402LF  page 182 : 1 = P3V3_AUX ; 2 = CLK_9ZXL045_P0_HIBW
R4492  Q_RES  10K 1% CHIP  pkg 0402LF  page 182 : 1 = CLK_9ZXL045_P0_HIBW ; 2 = GND
R4493  Q_RES  1 1% CHIP  pkg 0603LF  page 182 : 1 = P3V3_9ZXL045_P0 ; 2 = P3V3_9ZXL045_P0_VDDA
R4501  Q_RES  0 5% CHIP  pkg 0402LF  page 233 : 1 = CLK_GEN2_XTAL_IN_R ; 2 = CLK_GEN2_XTAL_IN
R4506  Q_RES  33.2 1% CHIP  pkg 0402LF  page 150 : 1 = SMB_CPU0_CPU1_SEC_SCL ; 2 = SMB_CPU0_CPU1_SEC_SCL_R
R4507  Q_RES  33.2 1% CHIP  pkg 0402LF  page 150 : 1 = SMB_CPU0_CPU1_SEC_SDA ; 2 = SMB_CPU0_CPU1_SEC_SDA_R
R4508  Q_RES  33.2 1% CHIP  pkg 0402LF  page 150 : 1 = SMB_1_PLD_3V3AUX_SCL ; 2 = SMB_1_PLD_3V3AUX_SCL_R3
R4509  Q_RES  33.2 1% CHIP  pkg 0402LF  page 150 : 1 = SMB_1_PLD_3V3AUX_SDA ; 2 = SMB_1_PLD_3V3AUX_SDA_R3
R4514  Q_RES  4.7K 1% EMPTY  pkg 0402LF  page 233 : 1 = CLK_GEN2_GPU_FPGA_OE_R2_N ; 2 = GND
R4515  Q_RES  100K 1% CHIP  pkg 0402LF  page 130 : 1 = P3V3_AUX ; 2 = UART_BMC_BIC_RX
R4518  Q_RES  10K 1% CHIP  pkg 0402LF  page 182 : 1 = FM_9ZXL045_P0_2_OE_N ; 2 = GND
R4519  Q_RES  10K 1% CHIP  pkg 0402LF  page 182 : 1 = FM_9ZXL045_P0_1_OE_N ; 2 = GND
R4520  Q_RES  10K 1% CHIP  pkg 0402LF  page 182 : 1 = FM_9ZXL045_P0_0_OE_N ; 2 = GND
R4521  Q_RES  1K 1% CHIP  pkg 0402LF  page 233 : 1 = P3V3_AUX ; 2 = CLK_GEN2_BMC_RC_OE_N
R4532  Q_RES  10K 1% CHIP  pkg 0402LF  page 135 : 1 = P3V3_AUX ; 2 = HP_LVC3_OCP_V3_1_P12V_PWRGD
R4535  Q_RES  0 5% CHIP  pkg 0402LF  page 28 : 1 = CLK_100M_CPU0_CLK01_R_DP ; 2 = CLK_100M_CPU0_CLK01_DP
R4536  Q_RES  0 5% CHIP  pkg 0402LF  page 28 : 1 = CLK_100M_CPU0_CLK01_R_DN ; 2 = CLK_100M_CPU0_CLK01_DN
R4537  Q_RES  0 5% CHIP  pkg 0402LF  page 111 : 1 = FM_P2E_EN_N ; 2 = CLK_GEN2_GPU_FPGA_OE_OR_N
R4543  Q_RES  1K 1% CHIP  pkg 0402LF  page 124 : 1 = P3V3_AUX ; 2 = HGX_DETECT_N
R4544  Q_RES  100K 1% EMPTY  pkg 0402LF  page 124 : 1 = HGX_DETECT_N ; 2 = GND
R4545  Q_RES  4.7K 5% CHIP  pkg 0402LF  page 124 : 1 = P3V3_AUX ; 2 = HGX_DETECT
R4546  Q_RES  100K 1% EMPTY  pkg 0402LF  page 124 : 1 = P3V3_AUX ; 2 = HGX_DETECT_N_ISO
R4547  Q_RES  100K 1% EMPTY  pkg 0402LF  page 124 : 1 = P3V3_AUX ; 2 = SWB_HSC_EN
R4548  Q_RES  100K 1% CHIP  pkg 0402LF  page 124 : 1 = SWB_HSC_EN ; 2 = GND
R4549  Q_RES  4.7K 5% EMPTY  pkg 0402LF  page 124 : 1 = P3V3_AUX ; 2 = SWB_HSC_EN_BUF_R
R4550  Q_RES  49.9 1% CHIP  pkg 0402LF  page 124 : 1 = SWB_HSC_EN_BUF_R ; 2 = SWB_HSC_EN_BUF
R4551  Q_RES  54.9K 1% EMPTY  pkg 0402LF  page 241 : 1 = P3V3_AUX ; 2 = HPDB_HSC_PWRGD
R4552  Q_RES  100K 1% CHIP  pkg 0402LF  page 241 : 1 = HPDB_HSC_PWRGD ; 2 = GND
R4553  Q_RES  4.7K 5% CHIP  pkg 0402LF  page 241 : 1 = P3V3_AUX ; 2 = HPDB_HSC_PWRGD_N
R4554  Q_RES  100K 1% CHIP  pkg 0402LF  page 241 : 1 = P3V3_AUX ; 2 = HPDB_HSC_PWRGD_ISO
R4555  Q_RES  4.7K 5% EMPTY  pkg 0402LF  page 124 : 1 = SWB_HSC_EN_BUF_R ; 2 = GND
R4556  Q_RES  33.2 1% CHIP  pkg 0402LF  page 81 : 1 = HGX_DETECT_N_R ; 2 = HGX_DETECT_N
R4557  Q_RES  33.2 1% CHIP  pkg 0402LF  page 81 : 1 = HPDB_HSC_PWRGD_ISO ; 2 = HPDB_HSC_PWRGD_ISO_R
R4558  Q_RES  33.2 1% CHIP  pkg 0402LF  page 81 : 1 = SWB_HSC_EN_R ; 2 = SWB_HSC_EN
R4559  Q_RES  100K 1% CHIP  pkg 0402LF  page 125 : 1 = SWB_HSC_PWRGD ; 2 = GND
R4560  Q_RES  4.7K 5% CHIP  pkg 0402LF  page 125 : 1 = P3V3_AUX ; 2 = SWB_HSC_PWRGD_N
R4561  Q_RES  100K 1% CHIP  pkg 0402LF  page 125 : 1 = P3V3_AUX ; 2 = SWB_HSC_PWRGD_ISO
R4562  Q_RES  100K 1% EMPTY  pkg 0402LF  page 125 : 1 = P3V3_AUX ; 2 = SWB_HSC_PWRGD
R4563  Q_RES  33.2 1% CHIP  pkg 0402LF  page 81 : 1 = SWB_HSC_PWRGD_ISO_R ; 2 = SWB_HSC_PWRGD_ISO
R4567  Q_RES  5.11K 1% CHIP  pkg 0402LF  page 257 : 1 = P3V3_PDB_AUX_ADC ; 2 = P1V581_PDB_ADC
R4568  Q_RES  4.7K 1% CHIP  pkg 0402LF  page 257 : 1 = P1V581_PDB_ADC ; 2 = GND
